(kicad_pcb
	(version 20241229)
	(generator "pcbnew")
	(generator_version "9.0")
	(general
		(thickness 1.6)
		(legacy_teardrops no)
	)
	(paper "A4")
	(title_block
		(title "LPDDR4 testbed")
		(date "2024-03-26")
		(rev "1.2.2")
		(comment 9 "footprints 60-65 of 66")
	)
	(layers
		(0 "F.Cu" signal)
		(4 "In1.Cu" power)
		(6 "In2.Cu" power)
		(8 "In3.Cu" signal)
		(10 "In4.Cu" signal)
		(2 "B.Cu" signal)
		(9 "F.Adhes" user "F.Adhesive")
		(11 "B.Adhes" user "B.Adhesive")
		(13 "F.Paste" user)
		(15 "B.Paste" user)
		(5 "F.SilkS" user "F.Silkscreen")
		(7 "B.SilkS" user "B.Silkscreen")
		(1 "F.Mask" user)
		(3 "B.Mask" user)
		(17 "Dwgs.User" user "User.Drawings")
		(19 "Cmts.User" user "User.Comments")
		(21 "Eco1.User" user "User.Eco1")
		(23 "Eco2.User" user "User.Eco2")
		(25 "Edge.Cuts" user)
		(27 "Margin" user)
		(31 "F.CrtYd" user "F.Courtyard")
		(29 "B.CrtYd" user "B.Courtyard")
		(35 "F.Fab" user)
		(33 "B.Fab" user)
	)
	(footprint "antmicro-footprints:C_0201"
		(layer "B.Cu")
		(at 149.375 89.15 -90)
		(descr "Capacitor SMD 0201")
		(tags "capacitor SMD 0201")
		(property "Reference" "C28"
			(at -0.9 -1.2 90)
			(layer "B.SilkS")
			(effects
				(font
					(size 0.7 0.7)
					(thickness 0.15)
				)
				(justify left bottom mirror)
			)
		)
		(property "Value" "C_100n_0201"
			(at 0 -1.4 90)
			(layer "B.Fab")
			(effects
				(font
					(size 0.7 0.7)
					(thickness 0.15)
				)
				(justify left bottom mirror)
			)
		)
		(property "Description" " "
			(at 0 0 270)
			(layer "F.Fab")
			(hide yes)
			(effects
				(font
					(size 1.27 1.27)
					(thickness 0.15)
				)
			)
		)
		(property "Author" "Antmicro"
			(at 60.225 238.525 0)
			(layer "B.Fab")
			(hide yes)
			(effects
				(font
					(size 1 1)
					(thickness 0.15)
				)
				(justify mirror)
			)
		)
		(property "Dielectric" ""
			(at 60.225 238.525 0)
			(layer "B.Fab")
			(hide yes)
			(effects
				(font
					(size 1 1)
					(thickness 0.15)
				)
				(justify mirror)
			)
		)
		(property "License" "Apache-2.0"
			(at 60.225 238.525 0)
			(layer "B.Fab")
			(hide yes)
			(effects
				(font
					(size 1 1)
					(thickness 0.15)
				)
				(justify mirror)
			)
		)
		(property "MPN" "CC0201KRX6S5BB104"
			(at 60.225 238.525 0)
			(layer "B.Fab")
			(hide yes)
			(effects
				(font
					(size 1 1)
					(thickness 0.15)
				)
				(justify mirror)
			)
		)
		(property "Manufacturer" "YAGEO"
			(at 60.225 238.525 0)
			(layer "B.Fab")
			(hide yes)
			(effects
				(font
					(size 1 1)
					(thickness 0.15)
				)
				(justify mirror)
			)
		)
		(property "Val" "100n"
			(at 60.225 238.525 0)
			(layer "B.Fab")
			(hide yes)
			(effects
				(font
					(size 1 1)
					(thickness 0.15)
				)
				(justify mirror)
			)
		)
		(property "Voltage" ""
			(at 60.225 238.525 0)
			(layer "B.Fab")
			(hide yes)
			(effects
				(font
					(size 1 1)
					(thickness 0.15)
				)
				(justify mirror)
			)
		)
		(sheetname "LPDDR4")
		(sheetfile "lpddr4.kicad_sch")
		(attr smd)
		(fp_rect
			(start -0.72 0.38)
			(end 0.72 -0.38)
			(stroke
				(width 0.05)
				(type solid)
			)
			(fill no)
			(layer "B.CrtYd")
		)
		(fp_rect
			(start 0.3 -0.15)
			(end -0.301 0.149)
			(stroke
				(width 0.15)
				(type solid)
			)
			(fill no)
			(layer "B.Fab")
		)
		(pad "" smd roundrect
			(at -0.349 0.002 270)
			(size 0.318 0.36)
			(layers "B.Paste")
			(roundrect_rratio 0.25)
		)
		(pad "" smd roundrect
			(at 0.341 0.002 270)
			(size 0.318 0.36)
			(layers "B.Paste")
			(roundrect_rratio 0.25)
		)
		(pad "1" smd roundrect
			(at -0.321 0.002 270)
			(size 0.46 0.4)
			(layers "B.Cu" "B.Mask")
			(roundrect_rratio 0.25)
			(net 36 "GND")
			(pintype "passive")
		)
		(pad "2" smd roundrect
			(at 0.32 0.002 270)
			(size 0.46 0.4)
			(layers "B.Cu" "B.Mask")
			(roundrect_rratio 0.25)
			(net 188 "VDD2")
			(pintype "passive")
		)
	)
	(footprint "antmicro-footprints:C_0201"
		(layer "B.Cu")
		(at 148.075 86.1 180)
		(descr "Capacitor SMD 0201")
		(tags "capacitor SMD 0201")
		(property "Reference" "C29"
			(at -0.9 0.45 0)
			(layer "B.SilkS")
			(effects
				(font
					(size 0.7 0.7)
					(thickness 0.15)
				)
				(justify left bottom mirror)
			)
		)
		(property "Value" "C_100n_0201"
			(at 0 -1.4 0)
			(layer "B.Fab")
			(effects
				(font
					(size 0.7 0.7)
					(thickness 0.15)
				)
				(justify left bottom mirror)
			)
		)
		(property "Description" " "
			(at 0 0 180)
			(layer "F.Fab")
			(hide yes)
			(effects
				(font
					(size 1.27 1.27)
					(thickness 0.15)
				)
			)
		)
		(property "Author" "Antmicro"
			(at 296.15 172.2 0)
			(layer "B.Fab")
			(hide yes)
			(effects
				(font
					(size 1 1)
					(thickness 0.15)
				)
				(justify mirror)
			)
		)
		(property "Dielectric" ""
			(at 296.15 172.2 0)
			(layer "B.Fab")
			(hide yes)
			(effects
				(font
					(size 1 1)
					(thickness 0.15)
				)
				(justify mirror)
			)
		)
		(property "License" "Apache-2.0"
			(at 296.15 172.2 0)
			(layer "B.Fab")
			(hide yes)
			(effects
				(font
					(size 1 1)
					(thickness 0.15)
				)
				(justify mirror)
			)
		)
		(property "MPN" "CC0201KRX6S5BB104"
			(at 296.15 172.2 0)
			(layer "B.Fab")
			(hide yes)
			(effects
				(font
					(size 1 1)
					(thickness 0.15)
				)
				(justify mirror)
			)
		)
		(property "Manufacturer" "YAGEO"
			(at 296.15 172.2 0)
			(layer "B.Fab")
			(hide yes)
			(effects
				(font
					(size 1 1)
					(thickness 0.15)
				)
				(justify mirror)
			)
		)
		(property "Val" "100n"
			(at 296.15 172.2 0)
			(layer "B.Fab")
			(hide yes)
			(effects
				(font
					(size 1 1)
					(thickness 0.15)
				)
				(justify mirror)
			)
		)
		(property "Voltage" ""
			(at 296.15 172.2 0)
			(layer "B.Fab")
			(hide yes)
			(effects
				(font
					(size 1 1)
					(thickness 0.15)
				)
				(justify mirror)
			)
		)
		(sheetname "LPDDR4")
		(sheetfile "lpddr4.kicad_sch")
		(attr smd)
		(fp_rect
			(start -0.72 0.38)
			(end 0.72 -0.38)
			(stroke
				(width 0.05)
				(type solid)
			)
			(fill no)
			(layer "B.CrtYd")
		)
		(fp_rect
			(start 0.3 -0.15)
			(end -0.301 0.149)
			(stroke
				(width 0.15)
				(type solid)
			)
			(fill no)
			(layer "B.Fab")
		)
		(pad "" smd roundrect
			(at -0.349 0.002 180)
			(size 0.318 0.36)
			(layers "B.Paste")
			(roundrect_rratio 0.25)
		)
		(pad "" smd roundrect
			(at 0.341 0.002 180)
			(size 0.318 0.36)
			(layers "B.Paste")
			(roundrect_rratio 0.25)
		)
		(pad "1" smd roundrect
			(at -0.321 0.002 180)
			(size 0.46 0.4)
			(layers "B.Cu" "B.Mask")
			(roundrect_rratio 0.25)
			(net 36 "GND")
			(pintype "passive")
		)
		(pad "2" smd roundrect
			(at 0.32 0.002 180)
			(size 0.46 0.4)
			(layers "B.Cu" "B.Mask")
			(roundrect_rratio 0.25)
			(net 187 "VDD1")
			(pintype "passive")
		)
	)
	(footprint "antmicro-footprints:C_0201"
		(layer "B.Cu")
		(at 153.075 86.15)
		(descr "Capacitor SMD 0201")
		(tags "capacitor SMD 0201")
		(property "Reference" "C30"
			(at -0.8 1.2 0)
			(layer "B.SilkS")
			(effects
				(font
					(size 0.7 0.7)
					(thickness 0.15)
				)
				(justify right bottom mirror)
			)
		)
		(property "Value" "C_100n_0201"
			(at 0 -1.4 0)
			(layer "B.Fab")
			(effects
				(font
					(size 0.7 0.7)
					(thickness 0.15)
				)
				(justify right bottom mirror)
			)
		)
		(property "Description" " "
			(at 0 0 0)
			(layer "F.Fab")
			(hide yes)
			(effects
				(font
					(size 1.27 1.27)
					(thickness 0.15)
				)
			)
		)
		(property "Author" "Antmicro"
			(at 0 0 0)
			(layer "B.Fab")
			(hide yes)
			(effects
				(font
					(size 1 1)
					(thickness 0.15)
				)
				(justify mirror)
			)
		)
		(property "Dielectric" ""
			(at 0 0 0)
			(layer "B.Fab")
			(hide yes)
			(effects
				(font
					(size 1 1)
					(thickness 0.15)
				)
				(justify mirror)
			)
		)
		(property "License" "Apache-2.0"
			(at 0 0 0)
			(layer "B.Fab")
			(hide yes)
			(effects
				(font
					(size 1 1)
					(thickness 0.15)
				)
				(justify mirror)
			)
		)
		(property "MPN" "CC0201KRX6S5BB104"
			(at 0 0 0)
			(layer "B.Fab")
			(hide yes)
			(effects
				(font
					(size 1 1)
					(thickness 0.15)
				)
				(justify mirror)
			)
		)
		(property "Manufacturer" "YAGEO"
			(at 0 0 0)
			(layer "B.Fab")
			(hide yes)
			(effects
				(font
					(size 1 1)
					(thickness 0.15)
				)
				(justify mirror)
			)
		)
		(property "Val" "100n"
			(at 0 0 0)
			(layer "B.Fab")
			(hide yes)
			(effects
				(font
					(size 1 1)
					(thickness 0.15)
				)
				(justify mirror)
			)
		)
		(property "Voltage" ""
			(at 0 0 0)
			(layer "B.Fab")
			(hide yes)
			(effects
				(font
					(size 1 1)
					(thickness 0.15)
				)
				(justify mirror)
			)
		)
		(sheetname "LPDDR4")
		(sheetfile "lpddr4.kicad_sch")
		(attr smd)
		(fp_rect
			(start -0.72 0.38)
			(end 0.72 -0.38)
			(stroke
				(width 0.05)
				(type solid)
			)
			(fill no)
			(layer "B.CrtYd")
		)
		(fp_rect
			(start 0.3 -0.15)
			(end -0.301 0.149)
			(stroke
				(width 0.15)
				(type solid)
			)
			(fill no)
			(layer "B.Fab")
		)
		(pad "" smd roundrect
			(at -0.349 0.002)
			(size 0.318 0.36)
			(layers "B.Paste")
			(roundrect_rratio 0.25)
		)
		(pad "" smd roundrect
			(at 0.341 0.002)
			(size 0.318 0.36)
			(layers "B.Paste")
			(roundrect_rratio 0.25)
		)
		(pad "1" smd roundrect
			(at -0.321 0.002)
			(size 0.46 0.4)
			(layers "B.Cu" "B.Mask")
			(roundrect_rratio 0.25)
			(net 36 "GND")
			(pintype "passive")
		)
		(pad "2" smd roundrect
			(at 0.32 0.002)
			(size 0.46 0.4)
			(layers "B.Cu" "B.Mask")
			(roundrect_rratio 0.25)
			(net 188 "VDD2")
			(pintype "passive")
		)
	)
	(footprint "antmicro-footprints:C_0201"
		(layer "B.Cu")
		(at 149.375 82.95 -90)
		(descr "Capacitor SMD 0201")
		(tags "capacitor SMD 0201")
		(property "Reference" "C32"
			(at -1.1 0.4 90)
			(layer "B.SilkS")
			(effects
				(font
					(size 0.7 0.7)
					(thickness 0.15)
				)
				(justify left bottom mirror)
			)
		)
		(property "Value" "C_100n_0201"
			(at 0 -1.4 90)
			(layer "B.Fab")
			(effects
				(font
					(size 0.7 0.7)
					(thickness 0.15)
				)
				(justify left bottom mirror)
			)
		)
		(property "Description" " "
			(at 0 0 270)
			(layer "F.Fab")
			(hide yes)
			(effects
				(font
					(size 1.27 1.27)
					(thickness 0.15)
				)
			)
		)
		(property "Author" "Antmicro"
			(at 66.425 232.325 0)
			(layer "B.Fab")
			(hide yes)
			(effects
				(font
					(size 1 1)
					(thickness 0.15)
				)
				(justify mirror)
			)
		)
		(property "Dielectric" ""
			(at 66.425 232.325 0)
			(layer "B.Fab")
			(hide yes)
			(effects
				(font
					(size 1 1)
					(thickness 0.15)
				)
				(justify mirror)
			)
		)
		(property "License" "Apache-2.0"
			(at 66.425 232.325 0)
			(layer "B.Fab")
			(hide yes)
			(effects
				(font
					(size 1 1)
					(thickness 0.15)
				)
				(justify mirror)
			)
		)
		(property "MPN" "CC0201KRX6S5BB104"
			(at 66.425 232.325 0)
			(layer "B.Fab")
			(hide yes)
			(effects
				(font
					(size 1 1)
					(thickness 0.15)
				)
				(justify mirror)
			)
		)
		(property "Manufacturer" "YAGEO"
			(at 66.425 232.325 0)
			(layer "B.Fab")
			(hide yes)
			(effects
				(font
					(size 1 1)
					(thickness 0.15)
				)
				(justify mirror)
			)
		)
		(property "Val" "100n"
			(at 66.425 232.325 0)
			(layer "B.Fab")
			(hide yes)
			(effects
				(font
					(size 1 1)
					(thickness 0.15)
				)
				(justify mirror)
			)
		)
		(property "Voltage" ""
			(at 66.425 232.325 0)
			(layer "B.Fab")
			(hide yes)
			(effects
				(font
					(size 1 1)
					(thickness 0.15)
				)
				(justify mirror)
			)
		)
		(sheetname "LPDDR4")
		(sheetfile "lpddr4.kicad_sch")
		(attr smd)
		(fp_rect
			(start -0.72 0.38)
			(end 0.72 -0.38)
			(stroke
				(width 0.05)
				(type solid)
			)
			(fill no)
			(layer "B.CrtYd")
		)
		(fp_rect
			(start 0.3 -0.15)
			(end -0.301 0.149)
			(stroke
				(width 0.15)
				(type solid)
			)
			(fill no)
			(layer "B.Fab")
		)
		(pad "" smd roundrect
			(at -0.349 0.002 270)
			(size 0.318 0.36)
			(layers "B.Paste")
			(roundrect_rratio 0.25)
		)
		(pad "" smd roundrect
			(at 0.341 0.002 270)
			(size 0.318 0.36)
			(layers "B.Paste")
			(roundrect_rratio 0.25)
		)
		(pad "1" smd roundrect
			(at -0.321 0.002 270)
			(size 0.46 0.4)
			(layers "B.Cu" "B.Mask")
			(roundrect_rratio 0.25)
			(net 36 "GND")
			(pintype "passive")
		)
		(pad "2" smd roundrect
			(at 0.32 0.002 270)
			(size 0.46 0.4)
			(layers "B.Cu" "B.Mask")
			(roundrect_rratio 0.25)
			(net 188 "VDD2")
			(pintype "passive")
		)
	)
	(footprint "antmicro-footprints:C_0201"
		(layer "B.Cu")
		(at 149.375 84.45 -90)
		(descr "Capacitor SMD 0201")
		(tags "capacitor SMD 0201")
		(property "Reference" "C33"
			(at -0.9 -1.2 90)
			(layer "B.SilkS")
			(effects
				(font
					(size 0.7 0.7)
					(thickness 0.15)
				)
				(justify left bottom mirror)
			)
		)
		(property "Value" "C_100n_0201"
			(at 0 -1.4 90)
			(layer "B.Fab")
			(effects
				(font
					(size 0.7 0.7)
					(thickness 0.15)
				)
				(justify left bottom mirror)
			)
		)
		(property "Description" " "
			(at 0 0 270)
			(layer "F.Fab")
			(hide yes)
			(effects
				(font
					(size 1.27 1.27)
					(thickness 0.15)
				)
			)
		)
		(property "Author" "Antmicro"
			(at 64.925 233.825 0)
			(layer "B.Fab")
			(hide yes)
			(effects
				(font
					(size 1 1)
					(thickness 0.15)
				)
				(justify mirror)
			)
		)
		(property "Dielectric" ""
			(at 64.925 233.825 0)
			(layer "B.Fab")
			(hide yes)
			(effects
				(font
					(size 1 1)
					(thickness 0.15)
				)
				(justify mirror)
			)
		)
		(property "License" "Apache-2.0"
			(at 64.925 233.825 0)
			(layer "B.Fab")
			(hide yes)
			(effects
				(font
					(size 1 1)
					(thickness 0.15)
				)
				(justify mirror)
			)
		)
		(property "MPN" "CC0201KRX6S5BB104"
			(at 64.925 233.825 0)
			(layer "B.Fab")
			(hide yes)
			(effects
				(font
					(size 1 1)
					(thickness 0.15)
				)
				(justify mirror)
			)
		)
		(property "Manufacturer" "YAGEO"
			(at 64.925 233.825 0)
			(layer "B.Fab")
			(hide yes)
			(effects
				(font
					(size 1 1)
					(thickness 0.15)
				)
				(justify mirror)
			)
		)
		(property "Val" "100n"
			(at 64.925 233.825 0)
			(layer "B.Fab")
			(hide yes)
			(effects
				(font
					(size 1 1)
					(thickness 0.15)
				)
				(justify mirror)
			)
		)
		(property "Voltage" ""
			(at 64.925 233.825 0)
			(layer "B.Fab")
			(hide yes)
			(effects
				(font
					(size 1 1)
					(thickness 0.15)
				)
				(justify mirror)
			)
		)
		(sheetname "LPDDR4")
		(sheetfile "lpddr4.kicad_sch")
		(attr smd)
		(fp_rect
			(start -0.72 0.38)
			(end 0.72 -0.38)
			(stroke
				(width 0.05)
				(type solid)
			)
			(fill no)
			(layer "B.CrtYd")
		)
		(fp_rect
			(start 0.3 -0.15)
			(end -0.301 0.149)
			(stroke
				(width 0.15)
				(type solid)
			)
			(fill no)
			(layer "B.Fab")
		)
		(pad "" smd roundrect
			(at -0.349 0.002 270)
			(size 0.318 0.36)
			(layers "B.Paste")
			(roundrect_rratio 0.25)
		)
		(pad "" smd roundrect
			(at 0.341 0.002 270)
			(size 0.318 0.36)
			(layers "B.Paste")
			(roundrect_rratio 0.25)
		)
		(pad "1" smd roundrect
			(at -0.321 0.002 270)
			(size 0.46 0.4)
			(layers "B.Cu" "B.Mask")
			(roundrect_rratio 0.25)
			(net 36 "GND")
			(pintype "passive")
		)
		(pad "2" smd roundrect
			(at 0.32 0.002 270)
			(size 0.46 0.4)
			(layers "B.Cu" "B.Mask")
			(roundrect_rratio 0.25)
			(net 188 "VDD2")
			(pintype "passive")
		)
	)
	(footprint "antmicro-footprints:C_0201"
		(layer "B.Cu")
		(at 144.975 86.1 180)
		(descr "Capacitor SMD 0201")
		(tags "capacitor SMD 0201")
		(property "Reference" "C35"
			(at -0.9 0.45 0)
			(layer "B.SilkS")
			(effects
				(font
					(size 0.7 0.7)
					(thickness 0.15)
				)
				(justify left bottom mirror)
			)
		)
		(property "Value" "C_100n_0201"
			(at 0 -1.4 0)
			(layer "B.Fab")
			(effects
				(font
					(size 0.7 0.7)
					(thickness 0.15)
				)
				(justify left bottom mirror)
			)
		)
		(property "Description" " "
			(at 0 0 180)
			(layer "F.Fab")
			(hide yes)
			(effects
				(font
					(size 1.27 1.27)
					(thickness 0.15)
				)
			)
		)
		(property "Author" "Antmicro"
			(at 289.95 172.2 0)
			(layer "B.Fab")
			(hide yes)
			(effects
				(font
					(size 1 1)
					(thickness 0.15)
				)
				(justify mirror)
			)
		)
		(property "Dielectric" ""
			(at 289.95 172.2 0)
			(layer "B.Fab")
			(hide yes)
			(effects
				(font
					(size 1 1)
					(thickness 0.15)
				)
				(justify mirror)
			)
		)
		(property "License" "Apache-2.0"
			(at 289.95 172.2 0)
			(layer "B.Fab")
			(hide yes)
			(effects
				(font
					(size 1 1)
					(thickness 0.15)
				)
				(justify mirror)
			)
		)
		(property "MPN" "CC0201KRX6S5BB104"
			(at 289.95 172.2 0)
			(layer "B.Fab")
			(hide yes)
			(effects
				(font
					(size 1 1)
					(thickness 0.15)
				)
				(justify mirror)
			)
		)
		(property "Manufacturer" "YAGEO"
			(at 289.95 172.2 0)
			(layer "B.Fab")
			(hide yes)
			(effects
				(font
					(size 1 1)
					(thickness 0.15)
				)
				(justify mirror)
			)
		)
		(property "Val" "100n"
			(at 289.95 172.2 0)
			(layer "B.Fab")
			(hide yes)
			(effects
				(font
					(size 1 1)
					(thickness 0.15)
				)
				(justify mirror)
			)
		)
		(property "Voltage" ""
			(at 289.95 172.2 0)
			(layer "B.Fab")
			(hide yes)
			(effects
				(font
					(size 1 1)
					(thickness 0.15)
				)
				(justify mirror)
			)
		)
		(sheetname "LPDDR4")
		(sheetfile "lpddr4.kicad_sch")
		(attr smd)
		(fp_rect
			(start -0.72 0.38)
			(end 0.72 -0.38)
			(stroke
				(width 0.05)
				(type solid)
			)
			(fill no)
			(layer "B.CrtYd")
		)
		(fp_rect
			(start 0.3 -0.15)
			(end -0.301 0.149)
			(stroke
				(width 0.15)
				(type solid)
			)
			(fill no)
			(layer "B.Fab")
		)
		(pad "" smd roundrect
			(at -0.349 0.002 180)
			(size 0.318 0.36)
			(layers "B.Paste")
			(roundrect_rratio 0.25)
		)
		(pad "" smd roundrect
			(at 0.341 0.002 180)
			(size 0.318 0.36)
			(layers "B.Paste")
			(roundrect_rratio 0.25)
		)
		(pad "1" smd roundrect
			(at -0.321 0.002 180)
			(size 0.46 0.4)
			(layers "B.Cu" "B.Mask")
			(roundrect_rratio 0.25)
			(net 36 "GND")
			(pintype "passive")
		)
		(pad "2" smd roundrect
			(at 0.32 0.002 180)
			(size 0.46 0.4)
			(layers "B.Cu" "B.Mask")
			(roundrect_rratio 0.25)
			(net 188 "VDD2")
			(pintype "passive")
		)
	)
)
